FILE_TYPE = CONNECTIVITY;
{Allegro Design Entry HDL 16.6-p007 (v16-6-112F) 10/10/2012}
"PAGE_NUMBER" = 99;
0"NC";
1"PVCCIO_CPU0\g";
2"PVPP_DEF\g";
3"PVPP_GHJ\g";
4"PVPP_KLM\g";
5"PVPP_ABC\g";
6"PVPP_ABC\g";
7"PVPP_ABC\g";
8"PVCCIO_CPU0\g";
9"PVCCIO_CPU0\g";
10"PVCCIO_CPU0\g";
11"GND\g";
12"PVCCIO_CPU1\g";
13"GND\g";
14"GND\g";
15"PVPP_DEF\g";
16"GND\g";
17"PVPP_GHJ\g";
18"GND\g";
19"PVCCIO_CPU1\g";
20"GND\g";
21"PVPP_KLM\g";
22"GND\g";
23"PVPP_DEF\g";
24"PVPP_GHJ\g";
25"PVCCIO_CPU0\g";
26"PVCCIO_CPU0\g";
27"PVCCIO_CPU1\g";
28"PVCCIO_CPU1\g";
29"PVPP_KLM\g";
30"PVCCIO_CPU1\g";
31"PVCCIO_CPU1\g";
32"GND\g";
33"SMB_DDR_ABC_VPP_SDA";
34"SMB_DDR_ABC_VPP_SCL";
35"SMB_DDR_ABC_VPP_SDA_R";
36"SMB_DDR_ABC_VPP_SCL_R";
37"SMB_DDR_KLM_VPP_SDA";
38"SMB_DDR_KLM_VPP_SCL";
39"SMB_DDR_GHJ_VPP_SCL";
40"SMB_DDR_GHJ_VPP_SDA";
41"SMB_DDR_DEF_VPP_SDA";
42"SMB_DDR_DEF_VPP_SCL";
43"SMB_DDR_DEF_VPP_SDA_R";
44"SMB_DDR_GHJ_VPP_SDA_R";
45"SMB_DDR_GHJ_VPP_SCL_R";
46"SMB_DDR_DEF_VPP_SCL_R";
47"SMB_DDR_KLM_VPP_SDA_R";
48"SMB_DDR_KLM_VPP_SCL_R";
49"SMB_DDR_ABC_SDA_G";
50"SMB_DDR_ABC_SCL_G";
51"TP_SMB_DDR_ABC_EN";
52"SMB_DDR_ABC_SDA_G_R";
53"SMB_DDR_ABC_SCL_G_R";
54"SMB_DDR_DEF_SDA_G";
55"SMB_DDR_GHJ_SDA_G";
56"SMB_DDR_GHJ_SCL_G";
57"SMB_DDR_DEF_SCL_G";
58"TP_SMB_DDR_DEF_EN";
59"SMB_DDR_KLM_SDA_G";
60"TP_SMB_DDR_GHJ_EN";
61"TP_SMB_DDR_KLM_EN";
62"SMB_DDR_KLM_SCL_G";
63"SMB_DDR_KLM_SCL_G_R";
64"SMB_DDR_GHJ_SCL_G_R";
65"SMB_DDR_GHJ_SDA_G_R";
66"SMB_DDR_DEF_SDA_G_R";
67"SMB_DDR_DEF_SCL_G_R";
68"SMB_DDR_KLM_SDA_G_R";
%"PVCCIO_CPU0"
"1","(1900,5100)","0","mstr_symbols","I1";
;
CDS_LIB"mstr_symbols"
VOLTAGE"1.1V"
BODY_TYPE"PLUMBING"
HDL_POWER"PVCCIO_CPU0";
"G\NAC"1;
%"RES"
"1","(1600,4300)","0","mstr_discrete","I10";
;
ROOM"MEM"
CDS_LOCATION"R4T10"
$SEC"1"
CDS_SEC"1"
CDS_LIB"mstr_discrete"
WATTAGE"1/16W"
MATERIAL"CHIP"
PACK_TYPE"0402"
TOLERANCE"1%"
VALUE"20.0"
PART_NUMBER"G21796-173"
LOCATION"R4T10";
"B"
$PN"2"33;
"A"
$PN"1"35;
%"RES"
"2","(1275,3600)","0","mstr_discrete","I101";
;
CDS_SEC"1"
ROOM"MEM"
CDS_LOCATION"R3R12"
SEC"1"
SEC_TYPE"0402"
BOM_COST"SM_CONTROLLER"
CDS_LIB"mstr_discrete"
WATTAGE"1/16W"
MATERIAL"CHIP"
PACK_TYPE"0402"
TOLERANCE"1.0%"
VALUE"665"
PART_NUMBER"G21796-235"
LOCATION"R3R12";
"A"
$PN"1"2;
"B"
$PN"2"43;
%"PVPP_DEF"
"1","(925,3900)","0","mstr_symbols","I102";
;
ROOM"SMB"
CDS_LIB"mstr_symbols"
BOM_COST"SM_CONTROLLER"
VOLTAGE"2.5V"
BODY_TYPE"PLUMBING"
HDL_POWER"PVPP_DEF";
"G\NAC"2;
%"RES"
"2","(925,3600)","0","mstr_discrete","I103";
;
CDS_SEC"1"
ROOM"MEM"
CDS_LOCATION"R3R5"
SEC"1"
SEC_TYPE"0402"
CDS_LIB"mstr_discrete"
BOM_COST"SM_CONTROLLER"
WATTAGE"1/16W"
MATERIAL"CHIP"
PACK_TYPE"0402"
TOLERANCE"1.0%"
VALUE"665"
PART_NUMBER"G21796-235"
LOCATION"R3R5";
"A"
$PN"1"2;
"B"
$PN"2"46;
%"RES"
"2","(1225,2450)","0","mstr_discrete","I104";
;
CDS_SEC"1"
ROOM"MEM"
CDS_LOCATION"R6U18"
SEC"1"
SEC_TYPE"0402"
BOM_COST"SM_CONTROLLER"
CDS_LIB"mstr_discrete"
WATTAGE"1/16W"
MATERIAL"CHIP"
PACK_TYPE"0402"
TOLERANCE"1.0%"
VALUE"665"
PART_NUMBER"G21796-235"
LOCATION"R6U18";
"A"
$PN"1"3;
"B"
$PN"2"44;
%"PVPP_GHJ"
"1","(875,2750)","0","mstr_symbols","I105";
;
ROOM"SMB"
CDS_LIB"mstr_symbols"
BOM_COST"SM_CONTROLLER"
VOLTAGE"2.5V"
BODY_TYPE"PLUMBING"
HDL_POWER"PVPP_GHJ";
"G\NAC"3;
%"RES"
"2","(875,2450)","0","mstr_discrete","I106";
;
CDS_SEC"1"
ROOM"MEM"
CDS_LOCATION"R6U17"
SEC"1"
SEC_TYPE"0402"
CDS_LIB"mstr_discrete"
BOM_COST"SM_CONTROLLER"
WATTAGE"1/16W"
MATERIAL"CHIP"
PACK_TYPE"0402"
TOLERANCE"1.0%"
VALUE"665"
PART_NUMBER"G21796-235"
LOCATION"R6U17";
"A"
$PN"1"3;
"B"
$PN"2"45;
%"RES"
"2","(1225,1250)","0","mstr_discrete","I107";
;
CDS_SEC"1"
ROOM"MEM"
CDS_LOCATION"R7M6"
SEC"1"
SEC_TYPE"0402"
BOM_COST"SM_CONTROLLER"
CDS_LIB"mstr_discrete"
WATTAGE"1/16W"
MATERIAL"CHIP"
PACK_TYPE"0402"
TOLERANCE"1.0%"
VALUE"665"
PART_NUMBER"G21796-235"
LOCATION"R7M6";
"A"
$PN"1"4;
"B"
$PN"2"47;
%"PVPP_KLM"
"1","(875,1550)","0","mstr_symbols","I108";
;
ROOM"SMB"
CDS_LIB"mstr_symbols"
BOM_COST"SM_CONTROLLER"
VOLTAGE"2.5V"
BODY_TYPE"PLUMBING"
HDL_POWER"PVPP_KLM";
"G\NAC"4;
%"RES"
"2","(875,1250)","0","mstr_discrete","I109";
;
CDS_SEC"1"
ROOM"MEM"
CDS_LOCATION"R7M1"
SEC"1"
SEC_TYPE"0402"
CDS_LIB"mstr_discrete"
BOM_COST"SM_CONTROLLER"
WATTAGE"1/16W"
MATERIAL"CHIP"
PACK_TYPE"0402"
TOLERANCE"1.0%"
VALUE"665"
PART_NUMBER"G21796-235"
LOCATION"R7M1";
"A"
$PN"1"4;
"B"
$PN"2"48;
%"RES"
"2","(1225,4650)","0","mstr_discrete","I11";
;
CDS_SEC"1"
ROOM"MEM"
CDS_LOCATION"R4T8"
SEC"1"
SEC_TYPE"0402"
CDS_LIB"mstr_discrete"
BOM_COST"SM_CONTROLLER"
WATTAGE"1/16W"
MATERIAL"CHIP"
PACK_TYPE"0402"
TOLERANCE"1.0%"
VALUE"665"
PART_NUMBER"G21796-235"
LOCATION"R4T8";
"A"
$PN"1"7;
"B"
$PN"2"35;
%"RES"
"1","(-1175,3250)","0","mstr_discrete","I110";
;
ROOM"MEM"
CDS_LOCATION"R3R14"
$SEC"1"
CDS_SEC"1"
BOM_COST"SM_CONTROLLER"
CDS_LIB"mstr_discrete"
WATTAGE"1/16W"
MATERIAL"CHIP"
PACK_TYPE"0402"
TOLERANCE"1%"
VALUE"10.0"
PART_NUMBER"G21796-066"
LOCATION"R3R14";
"B"
$PN"2"54;
"A"
$PN"1"66;
%"RES"
"1","(-1100,2100)","0","mstr_discrete","I111";
;
ROOM"MEM"
CDS_LOCATION"R6T4"
$SEC"1"
CDS_SEC"1"
BOM_COST"SM_CONTROLLER"
CDS_LIB"mstr_discrete"
WATTAGE"1/16W"
MATERIAL"CHIP"
PACK_TYPE"0402"
TOLERANCE"1%"
VALUE"10.0"
PART_NUMBER"G21796-066"
LOCATION"R6T4";
"B"
$PN"2"55;
"A"
$PN"1"65;
%"RES"
"1","(-1200,900)","0","mstr_discrete","I112";
;
ROOM"MEM"
CDS_LOCATION"R7M8"
$SEC"1"
CDS_SEC"1"
CDS_LIB"mstr_discrete"
BOM_COST"SM_CONTROLLER"
WATTAGE"1/16W"
MATERIAL"CHIP"
PACK_TYPE"0402"
TOLERANCE"1%"
VALUE"10.0"
PART_NUMBER"G21796-066"
LOCATION"R7M8";
"B"
$PN"2"59;
"A"
$PN"1"68;
%"PVPP_ABC"
"1","(1475,5100)","0","mstr_symbols","I113";
;
ROOM"SMB"
CDS_LIB"mstr_symbols"
BOM_COST"SM_CONTROLLER"
VOLTAGE"2.5V"
BODY_TYPE"PLUMBING"
HDL_POWER"PVPP_ABC";
"G\NAC"5;
%"PVPP_ABC"
"1","(650,4625)","0","mstr_symbols","I114";
;
ROOM"SMB"
CDS_LIB"mstr_symbols"
BOM_COST"SM_CONTROLLER"
VOLTAGE"2.5V"
BODY_TYPE"PLUMBING"
HDL_POWER"PVPP_ABC";
"G\NAC"6;
%"PVPP_ABC"
"1","(875,4950)","0","mstr_symbols","I12";
;
ROOM"SMB"
CDS_LIB"mstr_symbols"
BOM_COST"SM_CONTROLLER"
VOLTAGE"2.5V"
BODY_TYPE"PLUMBING"
HDL_POWER"PVPP_ABC";
"G\NAC"7;
%"RES"
"2","(875,4650)","0","mstr_discrete","I13";
;
CDS_SEC"1"
ROOM"MEM"
CDS_LOCATION"R4T7"
SEC"1"
SEC_TYPE"0402"
BOM_COST"SM_CONTROLLER"
CDS_LIB"mstr_discrete"
WATTAGE"1/16W"
MATERIAL"CHIP"
PACK_TYPE"0402"
TOLERANCE"1.0%"
VALUE"665"
PART_NUMBER"G21796-235"
LOCATION"R4T7";
"A"
$PN"1"7;
"B"
$PN"2"36;
%"PCA9617"
"1","(150,4300)","0","mstr_digital","I15";
;
ROOM"MEM"
CDS_LOCATION"U6F1"
$SEC"1"
CDS_SEC"1"
BOM_COST"SM_CONTROLLER"
CDS_LIB"mstr_digital"
PACK_TYPE"SSOP"
MATERIAL"IC"
PART_NUMBER"G81764-001"
LOCATION"U6F1"
POWER_GROUP"GND=GND";
"VCCA"
$PN"1"8;
"SCLA"
$PN"2"50;
"SDAA"
$PN"3"49;
"SCLB"
$PN"7"36;
"SDAB"
$PN"6"35;
"VCCB"
$PN"8"6;
"EN"
$PN"5"51;
%"PVCCIO_CPU0"
"1","(-475,4875)","0","mstr_symbols","I16";
;
CDS_LIB"mstr_symbols"
VOLTAGE"1.1V"
BODY_TYPE"PLUMBING"
HDL_POWER"PVCCIO_CPU0";
"G\NAC"8;
%"RES"
"2","(-650,4650)","2","mstr_discrete","I17";
;
ROOM"MEM"
CDS_LOCATION"R4T6"
$SEC"1"
CDS_SEC"1"
BOM_COST"SM_CONTROLLER"
CD_SEC"1"
SIGNAL_MODEL"DEFAULT_RESISTOR_750OHM_2_1"
CDS_LIB"mstr_discrete"
WATTAGE"1/16W"
MATERIAL"CHIP"
PACK_TYPE"0402"
TOLERANCE"1.0%"
VALUE"240"
PART_NUMBER"G21796-294"
LOCATION"R4T6";
"A"
$PN"1"9;
"B"
$PN"2"49;
%"PVCCIO_CPU0"
"1","(-900,4975)","0","mstr_symbols","I18";
;
CDS_LIB"mstr_symbols"
VOLTAGE"1.1V"
BODY_TYPE"PLUMBING"
HDL_POWER"PVCCIO_CPU0";
"G\NAC"9;
%"RES"
"2","(-1025,4650)","2","mstr_discrete","I19";
;
ROOM"MEM"
CDS_LOCATION"R4T5"
$SEC"1"
CDS_SEC"1"
BOM_COST"SM_CONTROLLER"
CDS_LIB"mstr_discrete"
SIGNAL_MODEL"DEFAULT_RESISTOR_750OHM_2_1"
CD_SEC"1"
WATTAGE"1/16W"
MATERIAL"CHIP"
PACK_TYPE"0402"
TOLERANCE"1.0%"
VALUE"240"
PART_NUMBER"G21796-294"
LOCATION"R4T5";
"A"
$PN"1"9;
"B"
$PN"2"50;
%"CAP_A"
"1","(1900,4925)","0","dev_discrete","I2";
;
$SEC"1"
CDS_SEC"1"
CDS_LIB"dev_discrete"
SIGNAL_MODEL"DEFAULT_CAPACITOR_100000pF_2_1"
CD_SEC"1"
BOM_COST"SM_CONTROLLER"
CDS_LOCATION"C6F2"
ROOM"MEM"
MATERIAL"X7R"
VOLTAGE"16V"
PACK_TYPE"0402V"
TOLERANCE"10%"
VALUE"0.1UF"
PART_NUMBER"A36096-030"
LOCATION"C6F2";
"B"
$PN"2"14;
"A"
$PN"1"1;
%"RES"
"1","(-1075,4300)","0","mstr_discrete","I20";
;
ROOM"MEM"
CDS_LOCATION"R4T4"
$SEC"1"
CDS_SEC"1"
BOM_COST"SM_CONTROLLER"
CDS_LIB"mstr_discrete"
WATTAGE"1/16W"
MATERIAL"CHIP"
PACK_TYPE"0402"
TOLERANCE"1%"
VALUE"10.0"
PART_NUMBER"G21796-066"
LOCATION"R4T4";
"B"
$PN"2"49;
"A"
$PN"1"52;
%"PVCCIO_CPU0"
"1","(2125,3950)","0","mstr_symbols","I21";
;
CDS_LIB"mstr_symbols"
VOLTAGE"1.1V"
BODY_TYPE"PLUMBING"
HDL_POWER"PVCCIO_CPU0";
"G\NAC"10;
%"GND"
"1","(2125,3525)","0","mstr_symbols","I22";
;
ROOM"SMB"
SIZE"1B"
CDS_LIB"mstr_symbols"
BOM_COST"SM_CONTROLLER"
VOLTAGE"0"
BODY_TYPE"PLUMBING"
HDL_POWER"GND";
"A\NAC"11;
%"CAP_A"
"1","(2125,3775)","0","dev_discrete","I23";
;
$SEC"1"
CDS_SEC"1"
CDS_LIB"dev_discrete"
BOM_COST"SM_CONTROLLER"
CD_SEC"1"
SIGNAL_MODEL"DEFAULT_CAPACITOR_100000pF_2_1"
CDS_LOCATION"C7E1"
ROOM"MEM"
MATERIAL"X7R"
VOLTAGE"16V"
PACK_TYPE"0402V"
TOLERANCE"10%"
VALUE"0.1UF"
PART_NUMBER"A36096-030"
LOCATION"C7E1";
"B"
$PN"2"11;
"A"
$PN"1"10;
%"PVCCIO_CPU1"
"1","(2225,2875)","0","mstr_symbols","I26";
;
CDS_LIB"mstr_symbols"
VOLTAGE"1.1V"
BODY_TYPE"PLUMBING"
HDL_POWER"PVCCIO_CPU1";
"G\NAC"12;
%"CAP_A"
"1","(2225,2700)","0","dev_discrete","I27";
;
$SEC"1"
CDS_SEC"1"
CDS_LIB"dev_discrete"
BOM_COST"SM_CONTROLLER"
CD_SEC"1"
SIGNAL_MODEL"DEFAULT_CAPACITOR_100000pF_2_1"
CDS_LOCATION"C4G22"
ROOM"MEM"
MATERIAL"X7R"
VOLTAGE"16V"
PACK_TYPE"0402V"
TOLERANCE"10%"
VALUE"0.1UF"
PART_NUMBER"A36096-030"
LOCATION"C4G22";
"B"
$PN"2"13;
"A"
$PN"1"12;
%"GND"
"1","(2225,2450)","0","mstr_symbols","I28";
;
ROOM"SMB"
SIZE"1B"
CDS_LIB"mstr_symbols"
BOM_COST"SM_CONTROLLER"
VOLTAGE"0"
BODY_TYPE"PLUMBING"
HDL_POWER"GND";
"A\NAC"13;
%"GND"
"1","(1900,4675)","0","mstr_symbols","I3";
;
ROOM"SMB"
BOM_COST"SM_CONTROLLER"
CDS_LIB"mstr_symbols"
SIZE"1B"
VOLTAGE"0"
BODY_TYPE"PLUMBING"
HDL_POWER"GND";
"A\NAC"14;
%"PVPP_DEF"
"1","(1625,3950)","0","mstr_symbols","I31";
;
CDS_LIB"mstr_symbols"
VOLTAGE"2.5V"
BODY_TYPE"PLUMBING"
HDL_POWER"PVPP_DEF";
"G\NAC"15;
%"CAP_A"
"1","(1625,3750)","0","dev_discrete","I32";
;
$SEC"1"
CDS_SEC"1"
CDS_LIB"dev_discrete"
BOM_COST"SM_CONTROLLER"
SIGNAL_MODEL"DEFAULT_CAPACITOR_100000pF_2_1"
CD_SEC"1"
CDS_LOCATION"C7E2"
ROOM"MEM"
MATERIAL"X7R"
VOLTAGE"16V"
PACK_TYPE"0402V"
TOLERANCE"10%"
VALUE"0.1UF"
PART_NUMBER"A36096-030"
LOCATION"C7E2";
"B"
$PN"2"16;
"A"
$PN"1"15;
%"GND"
"1","(1625,3500)","0","mstr_symbols","I33";
;
ROOM"SMB"
CDS_LIB"mstr_symbols"
SIZE"1B"
VOLTAGE"0"
BODY_TYPE"PLUMBING"
HDL_POWER"GND";
"A\NAC"16;
%"RES"
"1","(1600,3250)","0","mstr_discrete","I34";
;
ROOM"MEM"
CDS_LOCATION"R3R9"
$SEC"1"
CDS_SEC"1"
CDS_LIB"mstr_discrete"
WATTAGE"1/16W"
MATERIAL"CHIP"
PACK_TYPE"0402"
TOLERANCE"1%"
VALUE"20.0"
PART_NUMBER"G21796-173"
LOCATION"R3R9";
"B"
$PN"2"41;
"A"
$PN"1"43;
%"RES"
"1","(1600,3300)","0","mstr_discrete","I35";
;
ROOM"MEM"
CDS_LOCATION"R3R8"
$SEC"1"
CDS_SEC"1"
CDS_LIB"mstr_discrete"
WATTAGE"1/16W"
MATERIAL"CHIP"
PACK_TYPE"0402"
TOLERANCE"1%"
VALUE"20.0"
PART_NUMBER"G21796-173"
LOCATION"R3R8";
"B"
$PN"2"42;
"A"
$PN"1"46;
%"PVPP_GHJ"
"1","(1650,2875)","0","mstr_symbols","I39";
;
ROOM"SMB"
CDS_LIB"mstr_symbols"
BOM_COST"SM_CONTROLLER"
VOLTAGE"2.5V"
BODY_TYPE"PLUMBING"
HDL_POWER"PVPP_GHJ";
"G\NAC"17;
%"GND"
"1","(1650,2425)","0","mstr_symbols","I40";
;
ROOM"SMB"
BOM_COST"SM_CONTROLLER"
CDS_LIB"mstr_symbols"
SIZE"1B"
VOLTAGE"0"
BODY_TYPE"PLUMBING"
HDL_POWER"GND";
"A\NAC"18;
%"CAP_A"
"1","(1650,2675)","0","dev_discrete","I41";
;
$SEC"1"
CDS_SEC"1"
CDS_LIB"dev_discrete"
CD_SEC"1"
SIGNAL_MODEL"DEFAULT_CAPACITOR_100000pF_2_1"
BOM_COST"SM_CONTROLLER"
CDS_LOCATION"C4G25"
ROOM"MEM"
MATERIAL"X7R"
VOLTAGE"16V"
PACK_TYPE"0402V"
TOLERANCE"10%"
VALUE"0.1UF"
PART_NUMBER"A36096-030"
LOCATION"C4G25";
"B"
$PN"2"18;
"A"
$PN"1"17;
%"RES"
"1","(1600,2150)","0","mstr_discrete","I42";
;
ROOM"MEM"
CDS_LOCATION"R6U13"
$SEC"1"
CDS_SEC"1"
CDS_LIB"mstr_discrete"
WATTAGE"1/16W"
MATERIAL"CHIP"
PACK_TYPE"0402"
TOLERANCE"1%"
VALUE"20.0"
PART_NUMBER"G21796-173"
LOCATION"R6U13";
"B"
$PN"2"39;
"A"
$PN"1"45;
%"RES"
"1","(1600,2100)","0","mstr_discrete","I43";
;
ROOM"MEM"
CDS_LOCATION"R6U14"
$SEC"1"
CDS_SEC"1"
CDS_LIB"mstr_discrete"
WATTAGE"1/16W"
MATERIAL"CHIP"
PACK_TYPE"0402"
TOLERANCE"1%"
VALUE"20.0"
PART_NUMBER"G21796-173"
LOCATION"R6U14";
"B"
$PN"2"40;
"A"
$PN"1"44;
%"CAP_A"
"1","(2250,1525)","0","dev_discrete","I47";
;
$SEC"1"
CDS_SEC"1"
CDS_LIB"dev_discrete"
BOM_COST"SM_CONTROLLER"
SIGNAL_MODEL"DEFAULT_CAPACITOR_100000pF_2_1"
CD_SEC"1"
CDS_LOCATION"C3B4"
ROOM"MEM"
MATERIAL"X7R"
VOLTAGE"16V"
PACK_TYPE"0402V"
TOLERANCE"10%"
VALUE"0.1UF"
PART_NUMBER"A36096-030"
LOCATION"C3B4";
"B"
$PN"2"20;
"A"
$PN"1"19;
%"PVCCIO_CPU1"
"1","(2250,1700)","0","mstr_symbols","I48";
;
CDS_LIB"mstr_symbols"
VOLTAGE"1.1V"
BODY_TYPE"PLUMBING"
HDL_POWER"PVCCIO_CPU1";
"G\NAC"19;
%"GND"
"1","(2250,1275)","0","mstr_symbols","I49";
;
ROOM"SMB"
SIZE"1B"
CDS_LIB"mstr_symbols"
BOM_COST"SM_CONTROLLER"
VOLTAGE"0"
BODY_TYPE"PLUMBING"
HDL_POWER"GND";
"A\NAC"20;
%"PVPP_KLM"
"1","(1675,1700)","0","mstr_symbols","I52";
;
ROOM"SMB"
CDS_LIB"mstr_symbols"
BOM_COST"SM_CONTROLLER"
VOLTAGE"2.5V"
BODY_TYPE"PLUMBING"
HDL_POWER"PVPP_KLM";
"G\NAC"21;
%"CAP_A"
"1","(1675,1500)","0","dev_discrete","I53";
;
$SEC"1"
CDS_SEC"1"
CDS_LIB"dev_discrete"
SIGNAL_MODEL"DEFAULT_CAPACITOR_100000pF_2_1"
CD_SEC"1"
BOM_COST"SM_CONTROLLER"
CDS_LOCATION"C3B5"
ROOM"MEM"
MATERIAL"X7R"
VOLTAGE"16V"
PACK_TYPE"0402V"
TOLERANCE"10%"
VALUE"0.1UF"
PART_NUMBER"A36096-030"
LOCATION"C3B5";
"B"
$PN"2"22;
"A"
$PN"1"21;
%"GND"
"1","(1675,1250)","0","mstr_symbols","I54";
;
ROOM"SMB"
BOM_COST"SM_CONTROLLER"
SIZE"1B"
CDS_LIB"mstr_symbols"
VOLTAGE"0"
BODY_TYPE"PLUMBING"
HDL_POWER"GND";
"A\NAC"22;
%"RES"
"1","(1600,900)","0","mstr_discrete","I55";
;
ROOM"MEM"
CDS_LOCATION"R7M5"
$SEC"1"
CDS_SEC"1"
CDS_LIB"mstr_discrete"
WATTAGE"1/16W"
MATERIAL"CHIP"
PACK_TYPE"0402"
TOLERANCE"1%"
VALUE"20.0"
PART_NUMBER"G21796-173"
LOCATION"R7M5";
"B"
$PN"2"37;
"A"
$PN"1"47;
%"RES"
"1","(1600,950)","0","mstr_discrete","I56";
;
ROOM"MEM"
CDS_LOCATION"R7M4"
$SEC"1"
CDS_SEC"1"
CDS_LIB"mstr_discrete"
WATTAGE"1/16W"
MATERIAL"CHIP"
PACK_TYPE"0402"
TOLERANCE"1%"
VALUE"20.0"
PART_NUMBER"G21796-173"
LOCATION"R7M4";
"B"
$PN"2"38;
"A"
$PN"1"48;
%"PVPP_DEF"
"1","(625,3575)","0","mstr_symbols","I60";
;
ROOM"SMB"
CDS_LIB"mstr_symbols"
BOM_COST"SM_CONTROLLER"
VOLTAGE"2.5V"
BODY_TYPE"PLUMBING"
HDL_POWER"PVPP_DEF";
"G\NAC"23;
%"PCA9617"
"1","(150,3250)","0","mstr_digital","I61";
;
ROOM"MEM"
CDS_LOCATION"U7E1"
$SEC"1"
CDS_SEC"1"
BOM_COST"SM_CONTROLLER"
CDS_LIB"mstr_digital"
PACK_TYPE"SSOP"
MATERIAL"IC"
PART_NUMBER"G81764-001"
LOCATION"U7E1"
POWER_GROUP"GND=GND";
"VCCA"
$PN"1"25;
"SCLA"
$PN"2"57;
"SDAA"
$PN"3"54;
"SCLB"
$PN"7"46;
"SDAB"
$PN"6"43;
"VCCB"
$PN"8"23;
"EN"
$PN"5"58;
%"PVPP_GHJ"
"1","(600,2425)","0","mstr_symbols","I62";
;
ROOM"SMB"
CDS_LIB"mstr_symbols"
BOM_COST"SM_CONTROLLER"
VOLTAGE"2.5V"
BODY_TYPE"PLUMBING"
HDL_POWER"PVPP_GHJ";
"G\NAC"24;
%"PCA9617"
"1","(150,2100)","0","mstr_digital","I63";
;
ROOM"MEM"
CDS_LOCATION"U4G1"
$SEC"1"
CDS_SEC"1"
BOM_COST"SM_CONTROLLER"
CDS_LIB"mstr_digital"
PACK_TYPE"SSOP"
MATERIAL"IC"
PART_NUMBER"G81764-001"
LOCATION"U4G1"
POWER_GROUP"GND=GND";
"VCCA"
$PN"1"27;
"SCLA"
$PN"2"56;
"SDAA"
$PN"3"55;
"SCLB"
$PN"7"45;
"SDAB"
$PN"6"44;
"VCCB"
$PN"8"24;
"EN"
$PN"5"60;
%"PVCCIO_CPU0"
"1","(-500,3825)","0","mstr_symbols","I64";
;
CDS_LIB"mstr_symbols"
VOLTAGE"1.1V"
BODY_TYPE"PLUMBING"
HDL_POWER"PVCCIO_CPU0";
"G\NAC"25;
%"RES"
"2","(-675,3600)","2","mstr_discrete","I65";
;
ROOM"MEM"
CDS_LOCATION"R3R13"
$SEC"1"
CDS_SEC"1"
BOM_COST"SM_CONTROLLER"
CD_SEC"1"
SIGNAL_MODEL"DEFAULT_RESISTOR_750OHM_2_1"
CDS_LIB"mstr_discrete"
WATTAGE"1/16W"
MATERIAL"CHIP"
PACK_TYPE"0402"
TOLERANCE"1.0%"
VALUE"240"
PART_NUMBER"G21796-294"
LOCATION"R3R13";
"A"
$PN"1"26;
"B"
$PN"2"54;
%"PVCCIO_CPU0"
"1","(-925,3925)","0","mstr_symbols","I66";
;
CDS_LIB"mstr_symbols"
VOLTAGE"1.1V"
BODY_TYPE"PLUMBING"
HDL_POWER"PVCCIO_CPU0";
"G\NAC"26;
%"RES"
"2","(-1050,3600)","2","mstr_discrete","I67";
;
CDS_LOCATION"R3P60"
ROOM"MEM"
$SEC"1"
CDS_SEC"1"
BOM_COST"SM_CONTROLLER"
CDS_LIB"mstr_discrete"
SIGNAL_MODEL"DEFAULT_RESISTOR_750OHM_2_1"
CD_SEC"1"
WATTAGE"1/16W"
MATERIAL"CHIP"
PACK_TYPE"0402"
TOLERANCE"1.0%"
VALUE"240"
PART_NUMBER"G21796-294"
LOCATION"R3P60";
"A"
$PN"1"26;
"B"
$PN"2"57;
%"PVCCIO_CPU1"
"1","(-525,2675)","0","mstr_symbols","I69";
;
CDS_LIB"mstr_symbols"
VOLTAGE"1.1V"
BODY_TYPE"PLUMBING"
HDL_POWER"PVCCIO_CPU1";
"G\NAC"27;
%"CAP_A"
"1","(1475,4900)","0","dev_discrete","I7";
;
$SEC"1"
CDS_SEC"1"
CDS_LIB"dev_discrete"
SIGNAL_MODEL"DEFAULT_CAPACITOR_100000pF_2_1"
CD_SEC"1"
BOM_COST"SM_CONTROLLER"
CDS_LOCATION"C6F3"
ROOM"MEM"
MATERIAL"X7R"
VOLTAGE"16V"
PACK_TYPE"0402V"
TOLERANCE"10%"
VALUE"0.1UF"
PART_NUMBER"A36096-030"
LOCATION"C6F3";
"B"
$PN"2"32;
"A"
$PN"1"5;
%"RES"
"2","(-700,2450)","2","mstr_discrete","I70";
;
ROOM"MEM"
CDS_LOCATION"R6T1"
$SEC"1"
CDS_SEC"1"
BOM_COST"SM_CONTROLLER"
SIGNAL_MODEL"DEFAULT_RESISTOR_750OHM_2_1"
CD_SEC"1"
CDS_LIB"mstr_discrete"
WATTAGE"1/16W"
MATERIAL"CHIP"
PACK_TYPE"0402"
TOLERANCE"1.0%"
VALUE"240"
PART_NUMBER"G21796-294"
LOCATION"R6T1";
"A"
$PN"1"28;
"B"
$PN"2"55;
%"PVCCIO_CPU1"
"1","(-950,2775)","0","mstr_symbols","I71";
;
CDS_LIB"mstr_symbols"
VOLTAGE"1.1V"
BODY_TYPE"PLUMBING"
HDL_POWER"PVCCIO_CPU1";
"G\NAC"28;
%"RES"
"2","(-1075,2450)","2","mstr_discrete","I72";
;
ROOM"MEM"
CDS_LOCATION"R6T2"
$SEC"1"
CDS_SEC"1"
BOM_COST"SM_CONTROLLER"
CD_SEC"1"
SIGNAL_MODEL"DEFAULT_RESISTOR_750OHM_2_1"
CDS_LIB"mstr_discrete"
WATTAGE"1/16W"
MATERIAL"CHIP"
PACK_TYPE"0402"
TOLERANCE"1.0%"
VALUE"240"
PART_NUMBER"G21796-294"
LOCATION"R6T2";
"A"
$PN"1"28;
"B"
$PN"2"56;
%"PVPP_KLM"
"1","(575,1225)","0","mstr_symbols","I74";
;
ROOM"SMB"
CDS_LIB"mstr_symbols"
BOM_COST"SM_CONTROLLER"
VOLTAGE"2.5V"
BODY_TYPE"PLUMBING"
HDL_POWER"PVPP_KLM";
"G\NAC"29;
%"PCA9617"
"1","(150,900)","0","mstr_digital","I75";
;
ROOM"MEM"
CDS_LOCATION"U3B1"
$SEC"1"
CDS_SEC"1"
BOM_COST"SM_CONTROLLER"
CDS_LIB"mstr_digital"
PACK_TYPE"SSOP"
MATERIAL"IC"
PART_NUMBER"G81764-001"
LOCATION"U3B1"
POWER_GROUP"GND=GND";
"VCCA"
$PN"1"30;
"SCLA"
$PN"2"62;
"SDAA"
$PN"3"59;
"SCLB"
$PN"7"48;
"SDAB"
$PN"6"47;
"VCCB"
$PN"8"29;
"EN"
$PN"5"61;
%"PVCCIO_CPU1"
"1","(-550,1475)","0","mstr_symbols","I76";
;
CDS_LIB"mstr_symbols"
VOLTAGE"1.1V"
BODY_TYPE"PLUMBING"
HDL_POWER"PVCCIO_CPU1";
"G\NAC"30;
%"RES"
"2","(-725,1250)","2","mstr_discrete","I77";
;
ROOM"MEM"
CDS_LOCATION"R7M7"
$SEC"1"
CDS_SEC"1"
BOM_COST"SM_CONTROLLER"
SIGNAL_MODEL"DEFAULT_RESISTOR_750OHM_2_1"
CD_SEC"1"
CDS_LIB"mstr_discrete"
WATTAGE"1/16W"
MATERIAL"CHIP"
PACK_TYPE"0402"
TOLERANCE"1.0%"
VALUE"240"
PART_NUMBER"G21796-294"
LOCATION"R7M7";
"A"
$PN"1"31;
"B"
$PN"2"59;
%"PVCCIO_CPU1"
"1","(-975,1575)","0","mstr_symbols","I78";
;
CDS_LIB"mstr_symbols"
VOLTAGE"1.1V"
BODY_TYPE"PLUMBING"
HDL_POWER"PVCCIO_CPU1";
"G\NAC"31;
%"RES"
"2","(-1100,1250)","2","mstr_discrete","I79";
;
ROOM"MEM"
CDS_LOCATION"R7M2"
$SEC"1"
CDS_SEC"1"
BOM_COST"SM_CONTROLLER"
SIGNAL_MODEL"DEFAULT_RESISTOR_750OHM_2_1"
CD_SEC"1"
CDS_LIB"mstr_discrete"
WATTAGE"1/16W"
MATERIAL"CHIP"
PACK_TYPE"0402"
TOLERANCE"1.0%"
VALUE"240"
PART_NUMBER"G21796-294"
LOCATION"R7M2";
"A"
$PN"1"31;
"B"
$PN"2"62;
%"GND"
"1","(1475,4650)","0","mstr_symbols","I8";
;
ROOM"SMB"
SIZE"1B"
CDS_LIB"mstr_symbols"
BOM_COST"SM_CONTROLLER"
VOLTAGE"0"
BODY_TYPE"PLUMBING"
HDL_POWER"GND";
"A\NAC"32;
%"RES"
"1","(-1500,4350)","0","mstr_discrete","I83";
;
ROOM"MEM"
CDS_LOCATION"R4T3"
$SEC"1"
CDS_SEC"1"
CDS_LIB"mstr_discrete"
BOM_COST"SM_CONTROLLER"
WATTAGE"1/16W"
MATERIAL"CHIP"
PACK_TYPE"0402"
TOLERANCE"1%"
VALUE"10.0"
PART_NUMBER"G21796-066"
LOCATION"R4T3";
"B"
$PN"2"50;
"A"
$PN"1"53;
%"RES"
"1","(-1575,3300)","0","mstr_discrete","I88";
;
ROOM"MEM"
CDS_LOCATION"R3R7"
$SEC"1"
CDS_SEC"1"
BOM_COST"SM_CONTROLLER"
CDS_LIB"mstr_discrete"
WATTAGE"1/16W"
MATERIAL"CHIP"
PACK_TYPE"0402"
TOLERANCE"1%"
VALUE"10.0"
PART_NUMBER"G21796-066"
LOCATION"R3R7";
"B"
$PN"2"57;
"A"
$PN"1"67;
%"RES"
"1","(1600,4350)","0","mstr_discrete","I9";
;
ROOM"MEM"
CDS_LOCATION"R4T9"
$SEC"1"
CDS_SEC"1"
CDS_LIB"mstr_discrete"
WATTAGE"1/16W"
MATERIAL"CHIP"
PACK_TYPE"0402"
TOLERANCE"1%"
VALUE"20.0"
PART_NUMBER"G21796-173"
LOCATION"R4T9";
"B"
$PN"2"34;
"A"
$PN"1"36;
%"RES"
"1","(-1475,2150)","0","mstr_discrete","I92";
;
ROOM"MEM"
CDS_LOCATION"R6T3"
$SEC"1"
CDS_SEC"1"
BOM_COST"SM_CONTROLLER"
CDS_LIB"mstr_discrete"
WATTAGE"1/16W"
MATERIAL"CHIP"
PACK_TYPE"0402"
TOLERANCE"1%"
VALUE"10.0"
PART_NUMBER"G21796-066"
LOCATION"R6T3";
"B"
$PN"2"56;
"A"
$PN"1"64;
%"RES"
"1","(-1575,950)","0","mstr_discrete","I98";
;
ROOM"MEM"
CDS_LOCATION"R7M3"
$SEC"1"
CDS_SEC"1"
CDS_LIB"mstr_discrete"
BOM_COST"SM_CONTROLLER"
WATTAGE"1/16W"
MATERIAL"CHIP"
PACK_TYPE"0402"
TOLERANCE"1%"
VALUE"10.0"
PART_NUMBER"G21796-066"
LOCATION"R7M3";
"B"
$PN"2"62;
"A"
$PN"1"63;
END.
